# S9S_MB_2U (Grand Teton) — schematic netlist excerpt (pin names and nets, part order shuffled) for the footprints in the layout excerpt that follows; sources: Cadence DE-HDL packaged netlist, KiCad conversion of 03242023_DA0F0TMBIJ0_F0T_Motherboard_J_brd_V01_OCP.brd

R910  Q_RES  240 1% CHIP  pkg 0402LF  page 235 : A = PVNN_TERM_CPU0 ; B = SMB_PEHPCPU0_GTL_R_SCL
C1409  Q_CAP  10UF 6.3V 20% X6S  pkg C0603  page 206 : A = P3V3_DB2000_VDD ; B = GND

(kicad_pcb
	(version 20260206)
	(generator "pcbnew")
	(generator_version "10.0")
	(general
		(thickness 1.6)
		(legacy_teardrops no)
	)
	(paper "A4")
	(title_block
		(title "03242023_DA0F0TMBIJ0_F0T_Motherboard_J_brd_V01_OCP.brd")
		(comment 1 "Grand Teton / footprints 4195-4196 of 6105")
	)
	(layers
		(0 "F.Cu" signal "TOP")
		(4 "In1.Cu" signal "GND")
		(6 "In2.Cu" signal "IN1")
		(8 "In3.Cu" signal "GND1")
		(10 "In4.Cu" signal "IN2")
		(12 "In5.Cu" signal "GND2")
		(14 "In6.Cu" signal "IN3")
		(16 "In7.Cu" signal "GND3")
		(18 "In8.Cu" signal "VCC")
		(20 "In9.Cu" signal "VCC1")
		(22 "In10.Cu" signal "GND4")
		(24 "In11.Cu" signal "IN4")
		(26 "In12.Cu" signal "GND5")
		(28 "In13.Cu" signal "IN5")
		(30 "In14.Cu" signal "GND6")
		(32 "In15.Cu" signal "IN6")
		(34 "In16.Cu" signal "GND7")
		(2 "B.Cu" signal "BOTTOM")
		(9 "F.Adhes" user "F.Adhesive")
		(11 "B.Adhes" user "B.Adhesive")
		(13 "F.Paste" user "Package Geometry/Pastemask Top")
		(15 "B.Paste" user "Package Geometry/Pastemask Bottom")
		(5 "F.SilkS" user "Ref Des/Silkscreen Top")
		(7 "B.SilkS" user "Ref Des/Silkscreen Bottom")
		(1 "F.Mask" user "Board Geometry/Soldermask Top")
		(3 "B.Mask" user "Board Geometry/Soldermask Bottom")
		(17 "Dwgs.User" user "User.Drawings")
		(19 "Cmts.User" user "User.Comments")
		(21 "Eco1.User" user "User.Eco1")
		(23 "Eco2.User" user "User.Eco2")
		(25 "Edge.Cuts" user "Board Geometry/Outline")
		(27 "Margin" user)
		(31 "F.CrtYd" user "Package Geometry/Place Bound Top")
		(29 "B.CrtYd" user "Package Geometry/Place Bound Bottom")
		(35 "F.Fab" user "Ref Des/Assembly Top")
		(33 "B.Fab" user "Ref Des/Assembly Bottom")
	)
	(footprint ""
		(layer "B.Cu")
		(at 228.71684 -125.202188 -90)
		(property "Reference" "C1409"
			(at 0 0 90)
			(layer "B.SilkS")
			(hide yes)
			(effects
				(font
					(size 1.27 1.27)
				)
				(justify mirror)
			)
		)
		(property "Value" ""
			(at 0 0 90)
			(layer "B.Fab")
			(effects
				(font
					(size 1.27 1.27)
				)
				(justify mirror)
			)
		)
		(duplicate_pad_numbers_are_jumpers no)
		(fp_line
			(start -1.2954 0.5842)
			(end 1.2954 0.5842)
			(stroke
				(width 0.1524)
				(type default)
			)
			(layer "B.SilkS")
		)
		(fp_line
			(start 1.2954 0.5842)
			(end 1.2954 -0.5842)
			(stroke
				(width 0.1524)
				(type default)
			)
			(layer "B.SilkS")
		)
		(fp_line
			(start -1.2954 -0.5842)
			(end -1.2954 0.5842)
			(stroke
				(width 0.1524)
				(type default)
			)
			(layer "B.SilkS")
		)
		(fp_line
			(start 0 -0.5842)
			(end 0 0.5842)
			(stroke
				(width 0.1524)
				(type default)
			)
			(layer "B.SilkS")
		)
		(fp_line
			(start 1.2954 -0.5842)
			(end -1.2954 -0.5842)
			(stroke
				(width 0.1524)
				(type default)
			)
			(layer "B.SilkS")
		)
		(fp_line
			(start -0.8636 0.4572)
			(end 0.8636 0.4572)
			(stroke
				(width 0.1)
				(type default)
			)
			(layer "B.Fab")
		)
		(fp_line
			(start 0.8636 0.4572)
			(end 0.8636 0.4064)
			(stroke
				(width 0.1)
				(type default)
			)
			(layer "B.Fab")
		)
		(fp_line
			(start -1.1938 0.4064)
			(end -0.8636 0.4064)
			(stroke
				(width 0.1)
				(type default)
			)
			(layer "B.Fab")
		)
		(fp_line
			(start -0.8636 0.4064)
			(end -0.8636 0.4572)
			(stroke
				(width 0.1)
				(type default)
			)
			(layer "B.Fab")
		)
		(fp_line
			(start 0.8636 0.4064)
			(end 1.1938 0.4064)
			(stroke
				(width 0.1)
				(type default)
			)
			(layer "B.Fab")
		)
		(fp_line
			(start 1.1938 0.4064)
			(end 1.1938 -0.4064)
			(stroke
				(width 0.1)
				(type default)
			)
			(layer "B.Fab")
		)
		(fp_line
			(start -1.1938 -0.4064)
			(end -1.1938 0.4064)
			(stroke
				(width 0.1)
				(type default)
			)
			(layer "B.Fab")
		)
		(fp_line
			(start -0.8636 -0.4064)
			(end -1.1938 -0.4064)
			(stroke
				(width 0.1)
				(type default)
			)
			(layer "B.Fab")
		)
		(fp_line
			(start 0.8636 -0.4064)
			(end 0.8636 -0.4572)
			(stroke
				(width 0.1)
				(type default)
			)
			(layer "B.Fab")
		)
		(fp_line
			(start 1.1938 -0.4064)
			(end 0.8636 -0.4064)
			(stroke
				(width 0.1)
				(type default)
			)
			(layer "B.Fab")
		)
		(fp_line
			(start -0.8636 -0.4572)
			(end -0.8636 -0.4064)
			(stroke
				(width 0.1)
				(type default)
			)
			(layer "B.Fab")
		)
		(fp_line
			(start 0.8636 -0.4572)
			(end -0.8636 -0.4572)
			(stroke
				(width 0.1)
				(type default)
			)
			(layer "B.Fab")
		)
		(pad "1" smd rect
			(at 0.7366 0 180)
			(size 0.7112 0.8128)
			(layers "B.Cu" "B.Mask" "B.Paste")
			(net "P3V3_DB2000_VDD")
		)
		(pad "2" smd rect
			(at -0.7366 0 180)
			(size 0.7112 0.8128)
			(layers "B.Cu" "B.Mask" "B.Paste")
			(net "GND")
		)
	)
	(footprint ""
		(layer "B.Cu")
		(at 373.112538 -187.99429 90)
		(property "Reference" "R910"
			(at 0 0 90)
			(layer "B.SilkS")
			(hide yes)
			(effects
				(font
					(size 1.27 1.27)
				)
				(justify mirror)
			)
		)
		(property "Value" ""
			(at 0 0 90)
			(layer "B.Fab")
			(effects
				(font
					(size 1.27 1.27)
				)
				(justify mirror)
			)
		)
		(duplicate_pad_numbers_are_jumpers no)
		(fp_line
			(start 0.7874 -0.4064)
			(end -0.7874 -0.4064)
			(stroke
				(width 0.1524)
				(type default)
			)
			(layer "B.SilkS")
		)
		(fp_line
			(start -0.7874 -0.4064)
			(end -0.7874 0.4064)
			(stroke
				(width 0.1524)
				(type default)
			)
			(layer "B.SilkS")
		)
		(fp_line
			(start 0.7874 0.4064)
			(end 0.7874 -0.4064)
			(stroke
				(width 0.1524)
				(type default)
			)
			(layer "B.SilkS")
		)
		(fp_line
			(start -0.7874 0.4064)
			(end 0.7874 0.4064)
			(stroke
				(width 0.1524)
				(type default)
			)
			(layer "B.SilkS")
		)
		(fp_line
			(start 0.67945 -0.305054)
			(end 0.12065 -0.305054)
			(stroke
				(width 0.1)
				(type default)
			)
			(layer "B.Fab")
		)
		(fp_line
			(start 0.12065 -0.305054)
			(end 0.12065 -0.2794)
			(stroke
				(width 0.1)
				(type default)
			)
			(layer "B.Fab")
		)
		(fp_line
			(start -0.12065 -0.3048)
			(end -0.67945 -0.3048)
			(stroke
				(width 0.1)
				(type default)
			)
			(layer "B.Fab")
		)
		(fp_line
			(start -0.67945 -0.3048)
			(end -0.67945 0.3048)
			(stroke
				(width 0.1)
				(type default)
			)
			(layer "B.Fab")
		)
		(fp_line
			(start 0.12065 -0.2794)
			(end -0.12065 -0.2794)
			(stroke
				(width 0.1)
				(type default)
			)
			(layer "B.Fab")
		)
		(fp_line
			(start -0.12065 -0.2794)
			(end -0.12065 -0.3048)
			(stroke
				(width 0.1)
				(type default)
			)
			(layer "B.Fab")
		)
		(fp_line
			(start 0.12065 0.2794)
			(end 0.12065 0.3048)
			(stroke
				(width 0.1)
				(type default)
			)
			(layer "B.Fab")
		)
		(fp_line
			(start -0.120396 0.2794)
			(end 0.12065 0.2794)
			(stroke
				(width 0.1)
				(type default)
			)
			(layer "B.Fab")
		)
		(fp_line
			(start 0.67945 0.3048)
			(end 0.67945 -0.305054)
			(stroke
				(width 0.1)
				(type default)
			)
			(layer "B.Fab")
		)
		(fp_line
			(start 0.12065 0.3048)
			(end 0.67945 0.3048)
			(stroke
				(width 0.1)
				(type default)
			)
			(layer "B.Fab")
		)
		(fp_line
			(start -0.120396 0.3048)
			(end -0.120396 0.2794)
			(stroke
				(width 0.1)
				(type default)
			)
			(layer "B.Fab")
		)
		(fp_line
			(start -0.67945 0.3048)
			(end -0.120396 0.3048)
			(stroke
				(width 0.1)
				(type default)
			)
			(layer "B.Fab")
		)
		(pad "1" smd circle
			(at 0.40005 0 270)
			(size 0 0)
			(layers "B.Cu" "B.Mask" "B.Paste")
			(net "PVNN_TERM_CPU0")
		)
		(pad "2" smd circle
			(at -0.40005 0 270)
			(size 0 0)
			(layers "B.Cu" "B.Mask" "B.Paste")
			(net "SMB_PEHPCPU0_GTL_R_SCL")
		)
	)
)
